(kicad_pcb
	(version 20260206)
	(generator "pcbnew")
	(generator_version "10.0")
	(general
		(thickness 1.6)
		(legacy_teardrops no)
	)
	(paper "A4")
	(title_block
		(title "fcb — 12433-1M.1206WZS1330.brd")
		(comment 1 "Open Vault / Knox (Wiwynn) / footprints 327-333 of 495")
	)
	(layers
		(0 "F.Cu" signal "TOP")
		(4 "In1.Cu" signal "L2GND")
		(6 "In2.Cu" signal "L3VCC")
		(2 "B.Cu" signal "BOTTOM")
		(9 "F.Adhes" user "F.Adhesive")
		(11 "B.Adhes" user "B.Adhesive")
		(13 "F.Paste" user "Package Geometry/Pastemask Top")
		(15 "B.Paste" user "Package Geometry/Pastemask Bottom")
		(5 "F.SilkS" user "Ref Des/Silkscreen Top")
		(7 "B.SilkS" user "Ref Des/Silkscreen Bottom")
		(1 "F.Mask" user "Board Geometry/Soldermask Top")
		(3 "B.Mask" user "Board Geometry/Soldermask Bottom")
		(17 "Dwgs.User" user "User.Drawings")
		(19 "Cmts.User" user "User.Comments")
		(21 "Eco1.User" user "User.Eco1")
		(23 "Eco2.User" user "User.Eco2")
		(25 "Edge.Cuts" user "Board Geometry/Outline")
		(27 "Margin" user)
		(31 "F.CrtYd" user "Package Geometry/Place Bound Top")
		(29 "B.CrtYd" user "Package Geometry/Place Bound Bottom")
		(35 "F.Fab" user "Ref Des/Assembly Top")
		(33 "B.Fab" user "Ref Des/Assembly Bottom")
	)
	(footprint ""
		(layer "F.Cu")
		(at 43.7896 -136.2456 90)
		(property "Reference" "PC90"
			(at 0 0 90)
			(layer "F.SilkS")
			(hide yes)
			(effects
				(font
					(size 1.27 1.27)
				)
			)
		)
		(property "Value" "SCD1U25V2KX-GP"
			(at 1.1811 -2.7051 90)
			(unlocked yes)
			(layer "F.Fab")
			(hide yes)
			(effects
				(font
					(size 1.016 1.016)
					(thickness 0.1524)
				)
			)
		)
		(property "Device Type" "C402H22"
			(at 1.1811 -4.2291 90)
			(unlocked yes)
			(layer "F.Fab")
			(hide yes)
			(effects
				(font
					(size 1.016 1.016)
					(thickness 0.1524)
				)
			)
		)
		(duplicate_pad_numbers_are_jumpers no)
		(fp_rect
			(start -0.4318 0.9525)
			(end 0.4318 -0.9525)
			(stroke
				(width 0)
				(type default)
			)
			(fill no)
			(layer "F.CrtYd")
		)
		(fp_rect
			(start -0.4318 0.9525)
			(end 0.4318 -0.9525)
			(stroke
				(width 0)
				(type default)
			)
			(fill no)
			(layer "F.Fab")
		)
		(pad "1" smd custom
			(at 0 -0.4445 90)
			(size 0.1524 0.1524)
			(layers "F.Cu" "F.Mask" "F.Paste")
			(net "P12VL_2490_VCC")
			(options
				(clearance outline)
				(anchor circle)
			)
			(primitives
				(gr_poly
					(pts
						(arc
							(start 0.3048 -0.2032)
							(mid 0.275042 -0.275042)
							(end 0.2032 -0.3048)
						)
						(arc
							(start -0.2032 -0.3048)
							(mid -0.275042 -0.275042)
							(end -0.3048 -0.2032)
						)
						(arc
							(start -0.3048 0.2032)
							(mid -0.275042 0.275042)
							(end -0.2032 0.3048)
						)
						(arc
							(start 0.2032 0.3048)
							(mid 0.275042 0.275042)
							(end 0.3048 0.2032)
						)
					)
					(width 0)
					(fill yes)
				)
			)
		)
		(pad "2" smd custom
			(at 0 0.4445 90)
			(size 0.1524 0.1524)
			(layers "F.Cu" "F.Mask" "F.Paste")
			(net "GND")
			(options
				(clearance outline)
				(anchor circle)
			)
			(primitives
				(gr_poly
					(pts
						(arc
							(start 0.3048 -0.2032)
							(mid 0.275042 -0.275042)
							(end 0.2032 -0.3048)
						)
						(arc
							(start -0.2032 -0.3048)
							(mid -0.275042 -0.275042)
							(end -0.3048 -0.2032)
						)
						(arc
							(start -0.3048 0.2032)
							(mid -0.275042 0.275042)
							(end -0.2032 0.3048)
						)
						(arc
							(start 0.2032 0.3048)
							(mid 0.275042 0.275042)
							(end 0.3048 0.2032)
						)
					)
					(width 0)
					(fill yes)
				)
			)
		)
	)
	(footprint ""
		(layer "F.Cu")
		(at 15.9258 -65.278)
		(property "Reference" "C57"
			(at 0 0 0)
			(layer "F.SilkS")
			(hide yes)
			(effects
				(font
					(size 1.27 1.27)
				)
			)
		)
		(property "Value" "SC220P50V3JN-GP"
			(at 0 -2.8194 0)
			(unlocked yes)
			(layer "F.Fab")
			(hide yes)
			(effects
				(font
					(size 1.016 1.016)
					(thickness 0.1524)
				)
			)
		)
		(property "Device Type" "C603H36"
			(at 0 -4.3434 0)
			(unlocked yes)
			(layer "F.Fab")
			(hide yes)
			(effects
				(font
					(size 1.016 1.016)
					(thickness 0.1524)
				)
			)
		)
		(duplicate_pad_numbers_are_jumpers no)
		(fp_line
			(start 0.508 0)
			(end -0.508 0)
			(stroke
				(width 0.2032)
				(type default)
			)
			(layer "F.SilkS")
		)
		(fp_rect
			(start -0.5842 1.3335)
			(end 0.5842 -1.3335)
			(stroke
				(width 0)
				(type default)
			)
			(fill no)
			(layer "F.CrtYd")
		)
		(fp_rect
			(start -0.5842 1.3335)
			(end 0.5842 -1.3335)
			(stroke
				(width 0)
				(type default)
			)
			(fill no)
			(layer "F.Fab")
		)
		(pad "1" smd custom
			(at 0 -0.762)
			(size 0.2159 0.2159)
			(layers "F.Cu" "F.Mask" "F.Paste")
			(net "I2C_C_SDA_CONN_R")
			(options
				(clearance outline)
				(anchor circle)
			)
			(primitives
				(gr_poly
					(pts
						(arc
							(start -0.3302 -0.4318)
							(mid -0.402042 -0.402042)
							(end -0.4318 -0.3302)
						)
						(arc
							(start -0.4318 0.3302)
							(mid -0.402042 0.402042)
							(end -0.3302 0.4318)
						)
						(arc
							(start 0.3302 0.4318)
							(mid 0.402042 0.402042)
							(end 0.4318 0.3302)
						)
						(arc
							(start 0.4318 -0.3302)
							(mid 0.402042 -0.402042)
							(end 0.3302 -0.4318)
						)
					)
					(width 0)
					(fill yes)
				)
			)
		)
		(pad "2" smd custom
			(at 0 0.762)
			(size 0.2159 0.2159)
			(layers "F.Cu" "F.Mask" "F.Paste")
			(net "GND")
			(options
				(clearance outline)
				(anchor circle)
			)
			(primitives
				(gr_poly
					(pts
						(arc
							(start -0.3302 -0.4318)
							(mid -0.402042 -0.402042)
							(end -0.4318 -0.3302)
						)
						(arc
							(start -0.4318 0.3302)
							(mid -0.402042 0.402042)
							(end -0.3302 0.4318)
						)
						(arc
							(start 0.3302 0.4318)
							(mid 0.402042 0.402042)
							(end 0.4318 0.3302)
						)
						(arc
							(start 0.4318 -0.3302)
							(mid 0.402042 -0.402042)
							(end 0.3302 -0.4318)
						)
					)
					(width 0)
					(fill yes)
				)
			)
		)
	)
	(footprint ""
		(layer "F.Cu")
		(at 15.6464 -53.2384 180)
		(property "Reference" "R357"
			(at 0 0 180)
			(layer "F.SilkS")
			(hide yes)
			(effects
				(font
					(size 1.27 1.27)
				)
			)
		)
		(property "Value" "10KR2F-2-GP"
			(at 0.064008 -3.993896 180)
			(unlocked yes)
			(layer "F.Fab")
			(hide yes)
			(effects
				(font
					(size 1.016 1.016)
					(thickness 0.1524)
				)
			)
		)
		(property "Device Type" "R402H16"
			(at 0.064008 -5.517896 180)
			(unlocked yes)
			(layer "F.Fab")
			(hide yes)
			(effects
				(font
					(size 1.016 1.016)
					(thickness 0.1524)
				)
			)
		)
		(duplicate_pad_numbers_are_jumpers no)
		(fp_line
			(start 0.508 -0.9398)
			(end -0.508 -0.9398)
			(stroke
				(width 0.1524)
				(type default)
			)
			(layer "F.SilkS")
		)
		(fp_line
			(start -0.508 -0.9398)
			(end -0.508 0.9398)
			(stroke
				(width 0.1524)
				(type default)
			)
			(layer "F.SilkS")
		)
		(fp_rect
			(start -0.508 0.9398)
			(end 0.508 -0.9398)
			(stroke
				(width 0)
				(type default)
			)
			(fill no)
			(layer "F.CrtYd")
		)
		(fp_rect
			(start -0.508 0.9398)
			(end 0.508 -0.9398)
			(stroke
				(width 0)
				(type default)
			)
			(fill no)
			(layer "F.Fab")
		)
		(pad "1" smd custom
			(at 0 -0.4445 180)
			(size 0.1397 0.1397)
			(layers "F.Cu" "F.Mask" "F.Paste")
			(net "P3V3")
			(options
				(clearance outline)
				(anchor circle)
			)
			(primitives
				(gr_poly
					(pts
						(arc
							(start -0.1778 -0.2794)
							(mid -0.249642 -0.249642)
							(end -0.2794 -0.1778)
						)
						(arc
							(start -0.2794 0.1778)
							(mid -0.249642 0.249642)
							(end -0.1778 0.2794)
						)
						(arc
							(start 0.1778 0.2794)
							(mid 0.249642 0.249642)
							(end 0.2794 0.1778)
						)
						(arc
							(start 0.2794 -0.1778)
							(mid 0.249642 -0.249642)
							(end 0.1778 -0.2794)
						)
					)
					(width 0)
					(fill yes)
				)
			)
		)
		(pad "2" smd custom
			(at 0 0.4445 180)
			(size 0.1397 0.1397)
			(layers "F.Cu" "F.Mask" "F.Paste")
			(net "FCB_HW_REVISION")
			(options
				(clearance outline)
				(anchor circle)
			)
			(primitives
				(gr_poly
					(pts
						(arc
							(start -0.1778 -0.2794)
							(mid -0.249642 -0.249642)
							(end -0.2794 -0.1778)
						)
						(arc
							(start -0.2794 0.1778)
							(mid -0.249642 0.249642)
							(end -0.1778 0.2794)
						)
						(arc
							(start 0.1778 0.2794)
							(mid 0.249642 0.249642)
							(end 0.2794 0.1778)
						)
						(arc
							(start 0.2794 -0.1778)
							(mid 0.249642 -0.249642)
							(end 0.1778 -0.2794)
						)
					)
					(width 0)
					(fill yes)
				)
			)
		)
	)
	(footprint ""
		(layer "F.Cu")
		(at 21.844508 -192.505838)
		(property "Reference" "F3"
			(at 0 0 0)
			(layer "F.SilkS")
			(hide yes)
			(effects
				(font
					(size 1.27 1.27)
				)
			)
		)
		(property "Value" "FUSE-3A15V-GP"
			(at 0.2286 -10.5918 0)
			(unlocked yes)
			(layer "F.Fab")
			(hide yes)
			(effects
				(font
					(size 1.016 1.016)
					(thickness 0.1524)
				)
			)
		)
		(property "Device Type" "FUSE-7452-UH50"
			(at 0.2286 -12.4968 0)
			(unlocked yes)
			(layer "F.Fab")
			(hide yes)
			(effects
				(font
					(size 1.016 1.016)
					(thickness 0.1524)
				)
			)
		)
		(duplicate_pad_numbers_are_jumpers no)
		(fp_line
			(start -4.9276 -2.921)
			(end 4.9276 -2.921)
			(stroke
				(width 0.1524)
				(type default)
			)
			(layer "F.SilkS")
		)
		(fp_line
			(start -4.9276 2.921)
			(end -4.9276 -2.921)
			(stroke
				(width 0.1524)
				(type default)
			)
			(layer "F.SilkS")
		)
		(fp_line
			(start 4.9276 -2.921)
			(end 4.9276 2.921)
			(stroke
				(width 0.1524)
				(type default)
			)
			(layer "F.SilkS")
		)
		(fp_line
			(start 4.9276 2.921)
			(end -4.9276 2.921)
			(stroke
				(width 0.1524)
				(type default)
			)
			(layer "F.SilkS")
		)
		(fp_poly
			(pts
				(xy -5.08 3.0988) (xy 5.08 3.0988) (xy 5.08 -3.0988) (xy -5.08 -3.0988)
			)
			(stroke
				(width 0)
				(type default)
			)
			(fill no)
			(layer "F.CrtYd")
		)
		(fp_poly
			(pts
				(xy -5.08 -3.0988) (xy 5.08 -3.0988) (xy 5.08 3.0988) (xy -5.08 3.0988)
			)
			(stroke
				(width 0)
				(type default)
			)
			(fill no)
			(layer "F.Fab")
		)
		(pad "1" smd rect
			(at -3.4036 0)
			(size 2.2098 5.2832)
			(layers "F.Cu" "F.Mask" "F.Paste")
			(net "P12V_FAN4")
		)
		(pad "2" smd rect
			(at 3.4036 0)
			(size 2.2098 5.2832)
			(layers "F.Cu" "F.Mask" "F.Paste")
			(net "P12V")
		)
	)
	(footprint ""
		(layer "F.Cu")
		(at 7.949946 -56.099964 -90)
		(property "Reference" "LED6"
			(at 0 0 270)
			(layer "F.SilkS")
			(hide yes)
			(effects
				(font
					(size 1.27 1.27)
				)
			)
		)
		(property "Value" "LED-RB-6-GP"
			(at -4.6736 3.8354 270)
			(unlocked yes)
			(layer "F.Fab")
			(hide yes)
			(effects
				(font
					(size 1.016 1.016)
					(thickness 0.1524)
				)
			)
		)
		(property "Device Type" "LED-100-3P-067106H325"
			(at -4.6736 2.3114 270)
			(unlocked yes)
			(layer "F.Fab")
			(hide yes)
			(effects
				(font
					(size 1.016 1.016)
					(thickness 0.1524)
				)
			)
		)
		(duplicate_pad_numbers_are_jumpers no)
		(fp_line
			(start -1.7526 10.414)
			(end -1.7526 6.6548)
			(stroke
				(width 0.1524)
				(type default)
			)
			(layer "F.SilkS")
		)
		(fp_line
			(start 1.7526 10.414)
			(end -1.7526 10.414)
			(stroke
				(width 0.1524)
				(type default)
			)
			(layer "F.SilkS")
		)
		(fp_line
			(start -3.6068 6.6548)
			(end -3.6068 -0.889)
			(stroke
				(width 0.1524)
				(type default)
			)
			(layer "F.SilkS")
		)
		(fp_line
			(start -1.7526 6.6548)
			(end -3.6068 6.6548)
			(stroke
				(width 0.1524)
				(type default)
			)
			(layer "F.SilkS")
		)
		(fp_line
			(start 1.7526 6.6548)
			(end 1.7526 10.414)
			(stroke
				(width 0.1524)
				(type default)
			)
			(layer "F.SilkS")
		)
		(fp_line
			(start 3.6068 6.6548)
			(end 1.7526 6.6548)
			(stroke
				(width 0.1524)
				(type default)
			)
			(layer "F.SilkS")
		)
		(fp_line
			(start -3.6068 -0.889)
			(end 3.6068 -0.889)
			(stroke
				(width 0.1524)
				(type default)
			)
			(layer "F.SilkS")
		)
		(fp_line
			(start 3.6068 -0.889)
			(end 3.6068 6.6548)
			(stroke
				(width 0.1524)
				(type default)
			)
			(layer "F.SilkS")
		)
		(fp_circle
			(center -2.54 0)
			(end -2.54 -0.9906)
			(stroke
				(width 0.3048)
				(type default)
			)
			(fill no)
			(layer "F.SilkS")
		)
		(fp_circle
			(center 0 0)
			(end 0 -0.9906)
			(stroke
				(width 0.3048)
				(type default)
			)
			(fill no)
			(layer "F.SilkS")
		)
		(fp_circle
			(center 2.54 0)
			(end 2.54 -0.9906)
			(stroke
				(width 0.3048)
				(type default)
			)
			(fill no)
			(layer "F.SilkS")
		)
		(fp_poly
			(pts
				(xy -1.4986 10.1473) (xy -1.4986 6.4008) (xy -3.3528 6.4008) (xy -3.3528 -0.3937) (xy 3.3528 -0.3937)
				(xy 3.3528 6.4008) (xy 1.4986 6.4008) (xy 1.4986 10.1473)
			)
			(stroke
				(width 0)
				(type default)
			)
			(fill no)
			(layer "F.CrtYd")
		)
		(fp_poly
			(pts
				(xy -2.0066 10.668) (xy 2.0066 10.668) (xy 2.0066 6.9088) (xy 3.8608 6.9088) (xy 3.8608 2.2098)
				(xy 3.3528 2.2098) (xy 3.3528 6.4008) (xy 1.4986 6.4008) (xy 1.4986 10.1473) (xy -1.4986 10.1473)
				(xy -1.4986 6.4008) (xy -3.3528 6.4008) (xy -3.3528 -0.3937) (xy 3.3528 -0.3937) (xy 3.3528 2.1971)
				(xy 3.8608 2.1971) (xy 3.8608 -1.143) (xy -3.8608 -1.143) (xy -3.8608 6.9088) (xy -2.0066 6.9088)
			)
			(stroke
				(width 0)
				(type default)
			)
			(fill no)
			(layer "F.CrtYd")
		)
		(fp_poly
			(pts
				(xy -2.0066 10.668) (xy -2.0066 6.9088) (xy -3.8608 6.9088) (xy -3.8608 -1.143) (xy 3.8608 -1.143)
				(xy 3.8608 6.9088) (xy 2.0066 6.9088) (xy 2.0066 10.668)
			)
			(stroke
				(width 0)
				(type default)
			)
			(fill no)
			(layer "F.Fab")
		)
		(pad "1" thru_hole circle
			(at 2.54 0 270)
			(size 1.27 1.27)
			(drill 0.889)
			(layers "*.Cu" "*.Mask")
			(remove_unused_layers no)
			(net "LED_DR_LED5_BLUE")
			(clearance 0.1651)
			(thermal_gap 0.1651)
		)
		(pad "2" thru_hole circle
			(at 0 0 270)
			(size 1.27 1.27)
			(drill 0.889)
			(layers "*.Cu" "*.Mask")
			(remove_unused_layers no)
			(net "LED_DR_LED5_K")
			(clearance 0.1651)
			(thermal_gap 0.1651)
		)
		(pad "3" thru_hole circle
			(at -2.54 0 270)
			(size 1.27 1.27)
			(drill 0.889)
			(layers "*.Cu" "*.Mask")
			(remove_unused_layers no)
			(net "LED_DR_LED5")
			(clearance 0.1651)
			(thermal_gap 0.1651)
		)
	)
	(footprint ""
		(layer "F.Cu")
		(at 31.36011 -171.677076)
		(property "Reference" "C11"
			(at 0 0 0)
			(layer "F.SilkS")
			(hide yes)
			(effects
				(font
					(size 1.27 1.27)
				)
			)
		)
		(property "Value" "SCD1U50V3KX-GP"
			(at 0 -2.8194 0)
			(unlocked yes)
			(layer "F.Fab")
			(hide yes)
			(effects
				(font
					(size 1.016 1.016)
					(thickness 0.1524)
				)
			)
		)
		(property "Device Type" "C603H36"
			(at 0 -4.3434 0)
			(unlocked yes)
			(layer "F.Fab")
			(hide yes)
			(effects
				(font
					(size 1.016 1.016)
					(thickness 0.1524)
				)
			)
		)
		(duplicate_pad_numbers_are_jumpers no)
		(fp_line
			(start 0.508 0)
			(end -0.508 0)
			(stroke
				(width 0.2032)
				(type default)
			)
			(layer "F.SilkS")
		)
		(fp_rect
			(start -0.5842 1.3335)
			(end 0.5842 -1.3335)
			(stroke
				(width 0)
				(type default)
			)
			(fill no)
			(layer "F.CrtYd")
		)
		(fp_rect
			(start -0.5842 1.3335)
			(end 0.5842 -1.3335)
			(stroke
				(width 0)
				(type default)
			)
			(fill no)
			(layer "F.Fab")
		)
		(pad "1" smd custom
			(at 0 -0.762)
			(size 0.2159 0.2159)
			(layers "F.Cu" "F.Mask" "F.Paste")
			(net "P3V3")
			(options
				(clearance outline)
				(anchor circle)
			)
			(primitives
				(gr_poly
					(pts
						(arc
							(start -0.3302 -0.4318)
							(mid -0.402042 -0.402042)
							(end -0.4318 -0.3302)
						)
						(arc
							(start -0.4318 0.3302)
							(mid -0.402042 0.402042)
							(end -0.3302 0.4318)
						)
						(arc
							(start 0.3302 0.4318)
							(mid 0.402042 0.402042)
							(end 0.4318 0.3302)
						)
						(arc
							(start 0.4318 -0.3302)
							(mid 0.402042 -0.402042)
							(end 0.3302 -0.4318)
						)
					)
					(width 0)
					(fill yes)
				)
			)
		)
		(pad "2" smd custom
			(at 0 0.762)
			(size 0.2159 0.2159)
			(layers "F.Cu" "F.Mask" "F.Paste")
			(net "GND")
			(options
				(clearance outline)
				(anchor circle)
			)
			(primitives
				(gr_poly
					(pts
						(arc
							(start -0.3302 -0.4318)
							(mid -0.402042 -0.402042)
							(end -0.4318 -0.3302)
						)
						(arc
							(start -0.4318 0.3302)
							(mid -0.402042 0.402042)
							(end -0.3302 0.4318)
						)
						(arc
							(start 0.3302 0.4318)
							(mid 0.402042 0.402042)
							(end 0.4318 0.3302)
						)
						(arc
							(start 0.4318 -0.3302)
							(mid 0.402042 -0.402042)
							(end 0.3302 -0.4318)
						)
					)
					(width 0)
					(fill yes)
				)
			)
		)
	)
	(footprint ""
		(layer "F.Cu")
		(at 18.1356 -17.768316)
		(property "Reference" "C27"
			(at 0 0 0)
			(layer "F.SilkS")
			(hide yes)
			(effects
				(font
					(size 1.27 1.27)
				)
			)
		)
		(property "Value" "SCD1U16V2KX-3GP"
			(at 1.1811 -2.7051 0)
			(unlocked yes)
			(layer "F.Fab")
			(hide yes)
			(effects
				(font
					(size 1.016 1.016)
					(thickness 0.1524)
				)
			)
		)
		(property "Device Type" "C402H22"
			(at 1.1811 -4.2291 0)
			(unlocked yes)
			(layer "F.Fab")
			(hide yes)
			(effects
				(font
					(size 1.016 1.016)
					(thickness 0.1524)
				)
			)
		)
		(duplicate_pad_numbers_are_jumpers no)
		(fp_rect
			(start -0.4318 0.9525)
			(end 0.4318 -0.9525)
			(stroke
				(width 0)
				(type default)
			)
			(fill no)
			(layer "F.CrtYd")
		)
		(fp_rect
			(start -0.4318 0.9525)
			(end 0.4318 -0.9525)
			(stroke
				(width 0)
				(type default)
			)
			(fill no)
			(layer "F.Fab")
		)
		(pad "1" smd custom
			(at 0 -0.4445)
			(size 0.1524 0.1524)
			(layers "F.Cu" "F.Mask" "F.Paste")
			(net "FAN_TACH12")
			(options
				(clearance outline)
				(anchor circle)
			)
			(primitives
				(gr_poly
					(pts
						(arc
							(start 0.3048 -0.2032)
							(mid 0.275042 -0.275042)
							(end 0.2032 -0.3048)
						)
						(arc
							(start -0.2032 -0.3048)
							(mid -0.275042 -0.275042)
							(end -0.3048 -0.2032)
						)
						(arc
							(start -0.3048 0.2032)
							(mid -0.275042 0.275042)
							(end -0.2032 0.3048)
						)
						(arc
							(start 0.2032 0.3048)
							(mid 0.275042 0.275042)
							(end 0.3048 0.2032)
						)
					)
					(width 0)
					(fill yes)
				)
			)
		)
		(pad "2" smd custom
			(at 0 0.4445)
			(size 0.1524 0.1524)
			(layers "F.Cu" "F.Mask" "F.Paste")
			(net "GND")
			(options
				(clearance outline)
				(anchor circle)
			)
			(primitives
				(gr_poly
					(pts
						(arc
							(start 0.3048 -0.2032)
							(mid 0.275042 -0.275042)
							(end 0.2032 -0.3048)
						)
						(arc
							(start -0.2032 -0.3048)
							(mid -0.275042 -0.275042)
							(end -0.3048 -0.2032)
						)
						(arc
							(start -0.3048 0.2032)
							(mid -0.275042 0.275042)
							(end -0.2032 0.3048)
						)
						(arc
							(start 0.2032 0.3048)
							(mid 0.275042 0.275042)
							(end 0.3048 0.2032)
						)
					)
					(width 0)
					(fill yes)
				)
			)
		)
	)
)
